(kicad_pcb
	(version 20260206)
	(generator "pcbnew")
	(generator_version "10.0")
	(general
		(thickness 1.6)
		(legacy_teardrops no)
	)
	(paper "A4")
	(title_block
		(title "04192023_DAF0TMB3IC0_F0TG_MB_C_brd_V02_OCP.brd")
		(comment 1 "Grand Teton / footprints 3359-3364 of 8354")
	)
	(layers
		(0 "F.Cu" signal "TOP")
		(4 "In1.Cu" signal "GND")
		(6 "In2.Cu" signal "IN1")
		(8 "In3.Cu" signal "GND1")
		(10 "In4.Cu" signal "IN2")
		(12 "In5.Cu" signal "GND2")
		(14 "In6.Cu" signal "IN3")
		(16 "In7.Cu" signal "GND3")
		(18 "In8.Cu" signal "VCC")
		(20 "In9.Cu" signal "VCC1")
		(22 "In10.Cu" signal "GND4")
		(24 "In11.Cu" signal "IN4")
		(26 "In12.Cu" signal "GND5")
		(28 "In13.Cu" signal "IN5")
		(30 "In14.Cu" signal "GND6")
		(32 "In15.Cu" signal "IN6")
		(34 "In16.Cu" signal "GND7")
		(2 "B.Cu" signal "BOTTOM")
		(9 "F.Adhes" user "F.Adhesive")
		(11 "B.Adhes" user "B.Adhesive")
		(13 "F.Paste" user "Package Geometry/Pastemask Top")
		(15 "B.Paste" user "Package Geometry/Pastemask Bottom")
		(5 "F.SilkS" user "Ref Des/Silkscreen Top")
		(7 "B.SilkS" user "Ref Des/Silkscreen Bottom")
		(1 "F.Mask" user "Board Geometry/Soldermask Top")
		(3 "B.Mask" user "Board Geometry/Soldermask Bottom")
		(17 "Dwgs.User" user "User.Drawings")
		(19 "Cmts.User" user "User.Comments")
		(21 "Eco1.User" user "User.Eco1")
		(23 "Eco2.User" user "User.Eco2")
		(25 "Edge.Cuts" user "Board Geometry/Outline")
		(27 "Margin" user)
		(31 "F.CrtYd" user "Package Geometry/Place Bound Top")
		(29 "B.CrtYd" user "Package Geometry/Place Bound Bottom")
		(35 "F.Fab" user "Ref Des/Assembly Top")
		(33 "B.Fab" user "Ref Des/Assembly Bottom")
	)
	(footprint ""
		(layer "F.Cu")
		(at 366.288574 5.082794 180)
		(property "Reference" "J65"
			(at -4.652264 -1.360932 90)
			(unlocked yes)
			(layer "F.SilkS")
			(effects
				(font
					(size 0.7874 0.5842)
					(thickness 0.1524)
				)
				(justify left)
			)
		)
		(property "Value" ""
			(at 0 0 180)
			(layer "F.Fab")
			(effects
				(font
					(size 1.27 1.27)
				)
			)
		)
		(duplicate_pad_numbers_are_jumpers no)
		(fp_line
			(start 1.2192 2.06756)
			(end -1.2192 2.06756)
			(stroke
				(width 0.1524)
				(type default)
			)
			(layer "F.SilkS")
		)
		(fp_line
			(start 1.2192 -2.06756)
			(end 1.2192 2.06756)
			(stroke
				(width 0.1524)
				(type default)
			)
			(layer "F.SilkS")
		)
		(fp_line
			(start -1.2192 2.06756)
			(end -1.2192 -2.06756)
			(stroke
				(width 0.1524)
				(type default)
			)
			(layer "F.SilkS")
		)
		(fp_line
			(start -1.2192 -2.06756)
			(end 1.2192 -2.06756)
			(stroke
				(width 0.1524)
				(type default)
			)
			(layer "F.SilkS")
		)
		(pad "" np_thru_hole circle
			(at -2.8829 -1.27 90)
			(size 1.0414 1.0414)
			(drill 1.0414)
			(layers "*.Cu" "*.Mask")
			(clearance 0.381)
			(thermal_gap 0.381)
		)
		(pad "" np_thru_hole circle
			(at -2.8829 1.27 90)
			(size 1.0414 1.0414)
			(drill 1.0414)
			(layers "*.Cu" "*.Mask")
			(clearance 0.381)
			(thermal_gap 0.381)
		)
		(pad "" np_thru_hole circle
			(at 3.4671 -1.27 90)
			(size 1.0414 1.0414)
			(drill 1.0414)
			(layers "*.Cu" "*.Mask")
			(clearance 0.381)
			(thermal_gap 0.381)
		)
		(pad "" np_thru_hole circle
			(at 3.4671 1.27 90)
			(size 1.0414 1.0414)
			(drill 1.0414)
			(layers "*.Cu" "*.Mask")
			(clearance 0.381)
			(thermal_gap 0.381)
		)
		(pad "1" smd rect
			(at 0.8255 -0.249936 90)
			(size 0.3048 0.508)
			(layers "F.Cu" "F.Mask" "F.Paste")
			(net "DELTA_L_85_5INCH_IN1_DP")
		)
		(pad "2" smd rect
			(at 0.8255 0.249936 90)
			(size 0.3048 0.508)
			(layers "F.Cu" "F.Mask" "F.Paste")
			(net "DELTA_L_85_5INCH_IN1_DN")
		)
		(pad "3" smd circle
			(at 0 0 180)
			(size 0 0)
			(layers "F.Cu" "F.Mask" "F.Paste")
			(net "DELTA_L_GND_1")
		)
		(zone
			(layer "F.Cu")
			(hatch none 0.5)
			(connect_pads
				(clearance 0)
			)
			(min_thickness 0.25)
			(keepout
				(tracks not_allowed)
				(vias allowed)
				(pads allowed)
				(copperpour not_allowed)
				(footprints allowed)
			)
			(placement
				(enabled no)
				(sheetname "")
			)
			(fill
				(thermal_gap 0.5)
				(thermal_bridge_width 0.5)
				(island_removal_mode 0)
			)
			(polygon
				(pts
					(xy 365.170974 5.631434) (xy 365.170974 5.53593) (xy 365.767874 5.53593) (xy 365.767874 5.12953)
					(xy 365.170974 5.12953) (xy 365.170974 5.036058) (xy 365.767874 5.036058) (xy 365.767874 4.629658)
					(xy 365.170974 4.629658) (xy 365.170974 4.534154) (xy 365.869474 4.534154) (xy 365.869474 5.631434)
				)
			)
		)
		(zone
			(layers "F.Cu" "B.Cu" "In1.Cu" "In2.Cu" "In3.Cu" "In4.Cu" "In5.Cu" "In6.Cu"
				"In7.Cu" "In8.Cu" "In9.Cu" "In10.Cu" "In11.Cu" "In12.Cu" "In13.Cu" "In14.Cu"
				"In15.Cu" "In16.Cu"
			)
			(hatch none 0.5)
			(connect_pads
				(clearance 0)
			)
			(min_thickness 0.25)
			(keepout
				(tracks not_allowed)
				(vias allowed)
				(pads allowed)
				(copperpour not_allowed)
				(footprints allowed)
			)
			(placement
				(enabled no)
				(sheetname "")
			)
			(fill
				(thermal_gap 0.5)
				(thermal_bridge_width 0.5)
				(island_removal_mode 0)
			)
			(polygon
				(pts
					(arc
						(start 363.748574 3.812794)
						(mid 361.894374 3.812794)
						(end 363.748574 3.812794)
					)
				)
			)
		)
		(zone
			(layers "F.Cu" "B.Cu" "In1.Cu" "In2.Cu" "In3.Cu" "In4.Cu" "In5.Cu" "In6.Cu"
				"In7.Cu" "In8.Cu" "In9.Cu" "In10.Cu" "In11.Cu" "In12.Cu" "In13.Cu" "In14.Cu"
				"In15.Cu" "In16.Cu"
			)
			(hatch none 0.5)
			(connect_pads
				(clearance 0)
			)
			(min_thickness 0.25)
			(keepout
				(tracks not_allowed)
				(vias allowed)
				(pads allowed)
				(copperpour not_allowed)
				(footprints allowed)
			)
			(placement
				(enabled no)
				(sheetname "")
			)
			(fill
				(thermal_gap 0.5)
				(thermal_bridge_width 0.5)
				(island_removal_mode 0)
			)
			(polygon
				(pts
					(arc
						(start 363.748574 6.352794)
						(mid 361.894374 6.352794)
						(end 363.748574 6.352794)
					)
				)
			)
		)
		(zone
			(layers "F.Cu" "B.Cu" "In1.Cu" "In2.Cu" "In3.Cu" "In4.Cu" "In5.Cu" "In6.Cu"
				"In7.Cu" "In8.Cu" "In9.Cu" "In10.Cu" "In11.Cu" "In12.Cu" "In13.Cu" "In14.Cu"
				"In15.Cu" "In16.Cu"
			)
			(hatch none 0.5)
			(connect_pads
				(clearance 0)
			)
			(min_thickness 0.25)
			(keepout
				(tracks not_allowed)
				(vias allowed)
				(pads allowed)
				(copperpour not_allowed)
				(footprints allowed)
			)
			(placement
				(enabled no)
				(sheetname "")
			)
			(fill
				(thermal_gap 0.5)
				(thermal_bridge_width 0.5)
				(island_removal_mode 0)
			)
			(polygon
				(pts
					(arc
						(start 370.098574 3.812794)
						(mid 368.244374 3.812794)
						(end 370.098574 3.812794)
					)
				)
			)
		)
		(zone
			(layers "F.Cu" "B.Cu" "In1.Cu" "In2.Cu" "In3.Cu" "In4.Cu" "In5.Cu" "In6.Cu"
				"In7.Cu" "In8.Cu" "In9.Cu" "In10.Cu" "In11.Cu" "In12.Cu" "In13.Cu" "In14.Cu"
				"In15.Cu" "In16.Cu"
			)
			(hatch none 0.5)
			(connect_pads
				(clearance 0)
			)
			(min_thickness 0.25)
			(keepout
				(tracks not_allowed)
				(vias allowed)
				(pads allowed)
				(copperpour not_allowed)
				(footprints allowed)
			)
			(placement
				(enabled no)
				(sheetname "")
			)
			(fill
				(thermal_gap 0.5)
				(thermal_bridge_width 0.5)
				(island_removal_mode 0)
			)
			(polygon
				(pts
					(arc
						(start 370.098574 6.352794)
						(mid 368.244374 6.352794)
						(end 370.098574 6.352794)
					)
				)
			)
		)
	)
	(footprint ""
		(layer "F.Cu")
		(at 239.50803 -47.003208 180)
		(property "Reference" "R2317"
			(at 0 0 180)
			(layer "F.SilkS")
			(hide yes)
			(effects
				(font
					(size 1.27 1.27)
				)
			)
		)
		(property "Value" ""
			(at 0 0 180)
			(layer "F.Fab")
			(effects
				(font
					(size 1.27 1.27)
				)
			)
		)
		(duplicate_pad_numbers_are_jumpers no)
		(fp_line
			(start 0.7874 0.4064)
			(end -0.7874 0.4064)
			(stroke
				(width 0.1524)
				(type default)
			)
			(layer "F.SilkS")
		)
		(fp_line
			(start 0.7874 -0.4064)
			(end 0.7874 0.4064)
			(stroke
				(width 0.1524)
				(type default)
			)
			(layer "F.SilkS")
		)
		(fp_line
			(start -0.7874 0.4064)
			(end -0.7874 -0.4064)
			(stroke
				(width 0.1524)
				(type default)
			)
			(layer "F.SilkS")
		)
		(fp_line
			(start -0.7874 -0.4064)
			(end 0.7874 -0.4064)
			(stroke
				(width 0.1524)
				(type default)
			)
			(layer "F.SilkS")
		)
		(fp_line
			(start 0.67945 0.3048)
			(end 0.120396 0.3048)
			(stroke
				(width 0.1)
				(type default)
			)
			(layer "F.Fab")
		)
		(fp_line
			(start 0.67945 -0.3048)
			(end 0.67945 0.3048)
			(stroke
				(width 0.1)
				(type default)
			)
			(layer "F.Fab")
		)
		(fp_line
			(start 0.12065 -0.2794)
			(end 0.12065 -0.3048)
			(stroke
				(width 0.1)
				(type default)
			)
			(layer "F.Fab")
		)
		(fp_line
			(start 0.12065 -0.3048)
			(end 0.67945 -0.3048)
			(stroke
				(width 0.1)
				(type default)
			)
			(layer "F.Fab")
		)
		(fp_line
			(start 0.120396 0.3048)
			(end 0.120396 0.2794)
			(stroke
				(width 0.1)
				(type default)
			)
			(layer "F.Fab")
		)
		(fp_line
			(start 0.120396 0.2794)
			(end -0.12065 0.2794)
			(stroke
				(width 0.1)
				(type default)
			)
			(layer "F.Fab")
		)
		(fp_line
			(start -0.12065 0.3048)
			(end -0.67945 0.3048)
			(stroke
				(width 0.1)
				(type default)
			)
			(layer "F.Fab")
		)
		(fp_line
			(start -0.12065 0.2794)
			(end -0.12065 0.3048)
			(stroke
				(width 0.1)
				(type default)
			)
			(layer "F.Fab")
		)
		(fp_line
			(start -0.12065 -0.2794)
			(end 0.12065 -0.2794)
			(stroke
				(width 0.1)
				(type default)
			)
			(layer "F.Fab")
		)
		(fp_line
			(start -0.12065 -0.305054)
			(end -0.12065 -0.2794)
			(stroke
				(width 0.1)
				(type default)
			)
			(layer "F.Fab")
		)
		(fp_line
			(start -0.67945 0.3048)
			(end -0.67945 -0.305054)
			(stroke
				(width 0.1)
				(type default)
			)
			(layer "F.Fab")
		)
		(fp_line
			(start -0.67945 -0.305054)
			(end -0.12065 -0.305054)
			(stroke
				(width 0.1)
				(type default)
			)
			(layer "F.Fab")
		)
		(pad "1" smd circle
			(at -0.40005 0 180)
			(size 0 0)
			(layers "F.Cu" "F.Mask" "F.Paste")
			(net "P3V3_E1S_0")
		)
		(pad "2" smd circle
			(at 0.40005 0 180)
			(size 0 0)
			(layers "F.Cu" "F.Mask" "F.Paste")
			(net "PU_E1S_0_DUALPORT_EN_N")
		)
	)
	(footprint ""
		(layer "F.Cu")
		(at 430.3776 -16.100298 90)
		(property "Reference" "C1577"
			(at 0 0 90)
			(layer "F.SilkS")
			(hide yes)
			(effects
				(font
					(size 1.27 1.27)
				)
			)
		)
		(property "Value" ""
			(at 0 0 90)
			(layer "F.Fab")
			(effects
				(font
					(size 1.27 1.27)
				)
			)
		)
		(duplicate_pad_numbers_are_jumpers no)
		(fp_line
			(start 0.299974 -0.150114)
			(end 0.299974 0.150114)
			(stroke
				(width 0.1)
				(type default)
			)
			(layer "F.Fab")
		)
		(fp_line
			(start -0.299974 -0.150114)
			(end 0.299974 -0.150114)
			(stroke
				(width 0.1)
				(type default)
			)
			(layer "F.Fab")
		)
		(fp_line
			(start 0.299974 0.150114)
			(end -0.299974 0.150114)
			(stroke
				(width 0.1)
				(type default)
			)
			(layer "F.Fab")
		)
		(fp_line
			(start -0.299974 0.150114)
			(end -0.299974 -0.150114)
			(stroke
				(width 0.1)
				(type default)
			)
			(layer "F.Fab")
		)
		(pad "1" smd rect
			(at -0.2667 0 90)
			(size 0.3048 0.381)
			(layers "F.Cu" "F.Mask" "F.Paste")
			(net "P5E_CPU0_G3_TX_C_DP<1>")
		)
		(pad "2" smd rect
			(at 0.2667 0 90)
			(size 0.3048 0.381)
			(layers "F.Cu" "F.Mask" "F.Paste")
			(net "P5E_CPU0_G3_TX_DP<1>")
		)
	)
	(footprint ""
		(layer "F.Cu")
		(at 352.425254 -344.586306 90)
		(property "Reference" "PR420"
			(at 0 0 90)
			(layer "F.SilkS")
			(hide yes)
			(effects
				(font
					(size 1.27 1.27)
				)
			)
		)
		(property "Value" ""
			(at 0 0 90)
			(layer "F.Fab")
			(effects
				(font
					(size 1.27 1.27)
				)
			)
		)
		(duplicate_pad_numbers_are_jumpers no)
		(fp_line
			(start 0.7874 -0.4064)
			(end 0.7874 0.4064)
			(stroke
				(width 0.1524)
				(type default)
			)
			(layer "F.SilkS")
		)
		(fp_line
			(start -0.7874 -0.4064)
			(end 0.7874 -0.4064)
			(stroke
				(width 0.1524)
				(type default)
			)
			(layer "F.SilkS")
		)
		(fp_line
			(start 0.7874 0.4064)
			(end -0.7874 0.4064)
			(stroke
				(width 0.1524)
				(type default)
			)
			(layer "F.SilkS")
		)
		(fp_line
			(start -0.7874 0.4064)
			(end -0.7874 -0.4064)
			(stroke
				(width 0.1524)
				(type default)
			)
			(layer "F.SilkS")
		)
		(fp_line
			(start -0.12065 -0.305054)
			(end -0.12065 -0.2794)
			(stroke
				(width 0.1)
				(type default)
			)
			(layer "F.Fab")
		)
		(fp_line
			(start -0.67945 -0.305054)
			(end -0.12065 -0.305054)
			(stroke
				(width 0.1)
				(type default)
			)
			(layer "F.Fab")
		)
		(fp_line
			(start 0.67945 -0.3048)
			(end 0.67945 0.3048)
			(stroke
				(width 0.1)
				(type default)
			)
			(layer "F.Fab")
		)
		(fp_line
			(start 0.12065 -0.3048)
			(end 0.67945 -0.3048)
			(stroke
				(width 0.1)
				(type default)
			)
			(layer "F.Fab")
		)
		(fp_line
			(start 0.12065 -0.2794)
			(end 0.12065 -0.3048)
			(stroke
				(width 0.1)
				(type default)
			)
			(layer "F.Fab")
		)
		(fp_line
			(start -0.12065 -0.2794)
			(end 0.12065 -0.2794)
			(stroke
				(width 0.1)
				(type default)
			)
			(layer "F.Fab")
		)
		(fp_line
			(start 0.120396 0.2794)
			(end -0.12065 0.2794)
			(stroke
				(width 0.1)
				(type default)
			)
			(layer "F.Fab")
		)
		(fp_line
			(start -0.12065 0.2794)
			(end -0.12065 0.3048)
			(stroke
				(width 0.1)
				(type default)
			)
			(layer "F.Fab")
		)
		(fp_line
			(start 0.67945 0.3048)
			(end 0.120396 0.3048)
			(stroke
				(width 0.1)
				(type default)
			)
			(layer "F.Fab")
		)
		(fp_line
			(start 0.120396 0.3048)
			(end 0.120396 0.2794)
			(stroke
				(width 0.1)
				(type default)
			)
			(layer "F.Fab")
		)
		(fp_line
			(start -0.12065 0.3048)
			(end -0.67945 0.3048)
			(stroke
				(width 0.1)
				(type default)
			)
			(layer "F.Fab")
		)
		(fp_line
			(start -0.67945 0.3048)
			(end -0.67945 -0.305054)
			(stroke
				(width 0.1)
				(type default)
			)
			(layer "F.Fab")
		)
		(pad "1" smd circle
			(at -0.40005 0 90)
			(size 0 0)
			(layers "F.Cu" "F.Mask" "F.Paste")
			(net "SW_PVDDCR_CPU1_P0_BOOT6")
		)
		(pad "2" smd circle
			(at 0.40005 0 90)
			(size 0 0)
			(layers "F.Cu" "F.Mask" "F.Paste")
			(net "SW_PVDDCR_CPU1_P0_BOOT6_R")
		)
	)
	(footprint ""
		(layer "F.Cu")
		(at 351.151444 -383.88163 -90)
		(property "Reference" "C944"
			(at 0 0 270)
			(layer "F.SilkS")
			(hide yes)
			(effects
				(font
					(size 1.27 1.27)
				)
			)
		)
		(property "Value" ""
			(at 0 0 270)
			(layer "F.Fab")
			(effects
				(font
					(size 1.27 1.27)
				)
			)
		)
		(duplicate_pad_numbers_are_jumpers no)
		(fp_line
			(start -0.299974 0.150114)
			(end -0.299974 -0.150114)
			(stroke
				(width 0.1)
				(type default)
			)
			(layer "F.Fab")
		)
		(fp_line
			(start 0.299974 0.150114)
			(end -0.299974 0.150114)
			(stroke
				(width 0.1)
				(type default)
			)
			(layer "F.Fab")
		)
		(fp_line
			(start -0.299974 -0.150114)
			(end 0.299974 -0.150114)
			(stroke
				(width 0.1)
				(type default)
			)
			(layer "F.Fab")
		)
		(fp_line
			(start 0.299974 -0.150114)
			(end 0.299974 0.150114)
			(stroke
				(width 0.1)
				(type default)
			)
			(layer "F.Fab")
		)
		(pad "1" smd rect
			(at -0.2667 0 270)
			(size 0.3048 0.381)
			(layers "F.Cu" "F.Mask" "F.Paste")
			(net "P5E_CPU0_P1_TX_C_DN<10>")
		)
		(pad "2" smd rect
			(at 0.2667 0 270)
			(size 0.3048 0.381)
			(layers "F.Cu" "F.Mask" "F.Paste")
			(net "P5E_CPU0_P1_TX_DN<10>")
		)
	)
	(footprint ""
		(layer "F.Cu")
		(at 205.159356 -114.249708)
		(property "Reference" "R4556"
			(at 0 0 0)
			(layer "F.SilkS")
			(hide yes)
			(effects
				(font
					(size 1.27 1.27)
				)
			)
		)
		(property "Value" ""
			(at 0 0 0)
			(layer "F.Fab")
			(effects
				(font
					(size 1.27 1.27)
				)
			)
		)
		(duplicate_pad_numbers_are_jumpers no)
		(fp_line
			(start -0.7874 -0.4064)
			(end 0.7874 -0.4064)
			(stroke
				(width 0.1524)
				(type default)
			)
			(layer "F.SilkS")
		)
		(fp_line
			(start -0.7874 0.4064)
			(end -0.7874 -0.4064)
			(stroke
				(width 0.1524)
				(type default)
			)
			(layer "F.SilkS")
		)
		(fp_line
			(start 0.7874 -0.4064)
			(end 0.7874 0.4064)
			(stroke
				(width 0.1524)
				(type default)
			)
			(layer "F.SilkS")
		)
		(fp_line
			(start 0.7874 0.4064)
			(end -0.7874 0.4064)
			(stroke
				(width 0.1524)
				(type default)
			)
			(layer "F.SilkS")
		)
		(fp_line
			(start -0.67945 -0.305054)
			(end -0.12065 -0.305054)
			(stroke
				(width 0.1)
				(type default)
			)
			(layer "F.Fab")
		)
		(fp_line
			(start -0.67945 0.3048)
			(end -0.67945 -0.305054)
			(stroke
				(width 0.1)
				(type default)
			)
			(layer "F.Fab")
		)
		(fp_line
			(start -0.12065 -0.305054)
			(end -0.12065 -0.2794)
			(stroke
				(width 0.1)
				(type default)
			)
			(layer "F.Fab")
		)
		(fp_line
			(start -0.12065 -0.2794)
			(end 0.12065 -0.2794)
			(stroke
				(width 0.1)
				(type default)
			)
			(layer "F.Fab")
		)
		(fp_line
			(start -0.12065 0.2794)
			(end -0.12065 0.3048)
			(stroke
				(width 0.1)
				(type default)
			)
			(layer "F.Fab")
		)
		(fp_line
			(start -0.12065 0.3048)
			(end -0.67945 0.3048)
			(stroke
				(width 0.1)
				(type default)
			)
			(layer "F.Fab")
		)
		(fp_line
			(start 0.120396 0.2794)
			(end -0.12065 0.2794)
			(stroke
				(width 0.1)
				(type default)
			)
			(layer "F.Fab")
		)
		(fp_line
			(start 0.120396 0.3048)
			(end 0.120396 0.2794)
			(stroke
				(width 0.1)
				(type default)
			)
			(layer "F.Fab")
		)
		(fp_line
			(start 0.12065 -0.3048)
			(end 0.67945 -0.3048)
			(stroke
				(width 0.1)
				(type default)
			)
			(layer "F.Fab")
		)
		(fp_line
			(start 0.12065 -0.2794)
			(end 0.12065 -0.3048)
			(stroke
				(width 0.1)
				(type default)
			)
			(layer "F.Fab")
		)
		(fp_line
			(start 0.67945 -0.3048)
			(end 0.67945 0.3048)
			(stroke
				(width 0.1)
				(type default)
			)
			(layer "F.Fab")
		)
		(fp_line
			(start 0.67945 0.3048)
			(end 0.120396 0.3048)
			(stroke
				(width 0.1)
				(type default)
			)
			(layer "F.Fab")
		)
		(pad "1" smd circle
			(at -0.40005 0)
			(size 0 0)
			(layers "F.Cu" "F.Mask" "F.Paste")
			(net "HGX_DETECT_N_R")
		)
		(pad "2" smd circle
			(at 0.40005 0)
			(size 0 0)
			(layers "F.Cu" "F.Mask" "F.Paste")
			(net "HGX_DETECT_N")
		)
	)
)
